# S9S_MB_2U (Grand Teton) — schematic netlist excerpt (pin names and nets, part order shuffled) for the footprints in the layout excerpt that follows; sources: Cadence DE-HDL packaged netlist, KiCad conversion of 03242023_DA0F0TMBIJ0_F0T_Motherboard_J_brd_V01_OCP.brd

C520  Q_CAP  47UF 4V 20% X6S  pkg C0805  page 76 : A = PVCCFA_EHV_FIVRA_CPU0 ; B = GND
PR3910  Q_RES  0 5% CHIP  pkg 0402LF  page 302 : A = HSC_VDD_R_1 ; B = HSC_VDD
R1821  Q_RES  200 1% CHIP  pkg 0402LF  page 229 : A = FM_SPD_REMOTE_EN_R ; B = FM_SPD_REMOTE_EN

(kicad_pcb
	(version 20260206)
	(generator "pcbnew")
	(generator_version "10.0")
	(general
		(thickness 1.6)
		(legacy_teardrops no)
	)
	(paper "A4")
	(title_block
		(title "03242023_DA0F0TMBIJ0_F0T_Motherboard_J_brd_V01_OCP.brd")
		(comment 1 "Grand Teton / footprints 4213-4215 of 6105")
	)
	(layers
		(0 "F.Cu" signal "TOP")
		(4 "In1.Cu" signal "GND")
		(6 "In2.Cu" signal "IN1")
		(8 "In3.Cu" signal "GND1")
		(10 "In4.Cu" signal "IN2")
		(12 "In5.Cu" signal "GND2")
		(14 "In6.Cu" signal "IN3")
		(16 "In7.Cu" signal "GND3")
		(18 "In8.Cu" signal "VCC")
		(20 "In9.Cu" signal "VCC1")
		(22 "In10.Cu" signal "GND4")
		(24 "In11.Cu" signal "IN4")
		(26 "In12.Cu" signal "GND5")
		(28 "In13.Cu" signal "IN5")
		(30 "In14.Cu" signal "GND6")
		(32 "In15.Cu" signal "IN6")
		(34 "In16.Cu" signal "GND7")
		(2 "B.Cu" signal "BOTTOM")
		(9 "F.Adhes" user "F.Adhesive")
		(11 "B.Adhes" user "B.Adhesive")
		(13 "F.Paste" user "Package Geometry/Pastemask Top")
		(15 "B.Paste" user "Package Geometry/Pastemask Bottom")
		(5 "F.SilkS" user "Ref Des/Silkscreen Top")
		(7 "B.SilkS" user "Ref Des/Silkscreen Bottom")
		(1 "F.Mask" user "Board Geometry/Soldermask Top")
		(3 "B.Mask" user "Board Geometry/Soldermask Bottom")
		(17 "Dwgs.User" user "User.Drawings")
		(19 "Cmts.User" user "User.Comments")
		(21 "Eco1.User" user "User.Eco1")
		(23 "Eco2.User" user "User.Eco2")
		(25 "Edge.Cuts" user "Board Geometry/Outline")
		(27 "Margin" user)
		(31 "F.CrtYd" user "Package Geometry/Place Bound Top")
		(29 "B.CrtYd" user "Package Geometry/Place Bound Bottom")
		(35 "F.Fab" user "Ref Des/Assembly Top")
		(33 "B.Fab" user "Ref Des/Assembly Bottom")
	)
	(footprint ""
		(layer "B.Cu")
		(at 194.357752 -403.022054 -90)
		(property "Reference" "PR3910"
			(at 0 0 90)
			(layer "B.SilkS")
			(hide yes)
			(effects
				(font
					(size 1.27 1.27)
				)
				(justify mirror)
			)
		)
		(property "Value" ""
			(at 0 0 90)
			(layer "B.Fab")
			(effects
				(font
					(size 1.27 1.27)
				)
				(justify mirror)
			)
		)
		(duplicate_pad_numbers_are_jumpers no)
		(fp_line
			(start -0.7874 0.4064)
			(end 0.7874 0.4064)
			(stroke
				(width 0.1524)
				(type default)
			)
			(layer "B.SilkS")
		)
		(fp_line
			(start 0.7874 0.4064)
			(end 0.7874 -0.4064)
			(stroke
				(width 0.1524)
				(type default)
			)
			(layer "B.SilkS")
		)
		(fp_line
			(start -0.7874 -0.4064)
			(end -0.7874 0.4064)
			(stroke
				(width 0.1524)
				(type default)
			)
			(layer "B.SilkS")
		)
		(fp_line
			(start 0.7874 -0.4064)
			(end -0.7874 -0.4064)
			(stroke
				(width 0.1524)
				(type default)
			)
			(layer "B.SilkS")
		)
		(fp_line
			(start -0.67945 0.3048)
			(end -0.120396 0.3048)
			(stroke
				(width 0.1)
				(type default)
			)
			(layer "B.Fab")
		)
		(fp_line
			(start -0.120396 0.3048)
			(end -0.120396 0.2794)
			(stroke
				(width 0.1)
				(type default)
			)
			(layer "B.Fab")
		)
		(fp_line
			(start 0.12065 0.3048)
			(end 0.67945 0.3048)
			(stroke
				(width 0.1)
				(type default)
			)
			(layer "B.Fab")
		)
		(fp_line
			(start 0.67945 0.3048)
			(end 0.67945 -0.305054)
			(stroke
				(width 0.1)
				(type default)
			)
			(layer "B.Fab")
		)
		(fp_line
			(start -0.120396 0.2794)
			(end 0.12065 0.2794)
			(stroke
				(width 0.1)
				(type default)
			)
			(layer "B.Fab")
		)
		(fp_line
			(start 0.12065 0.2794)
			(end 0.12065 0.3048)
			(stroke
				(width 0.1)
				(type default)
			)
			(layer "B.Fab")
		)
		(fp_line
			(start -0.12065 -0.2794)
			(end -0.12065 -0.3048)
			(stroke
				(width 0.1)
				(type default)
			)
			(layer "B.Fab")
		)
		(fp_line
			(start 0.12065 -0.2794)
			(end -0.12065 -0.2794)
			(stroke
				(width 0.1)
				(type default)
			)
			(layer "B.Fab")
		)
		(fp_line
			(start -0.67945 -0.3048)
			(end -0.67945 0.3048)
			(stroke
				(width 0.1)
				(type default)
			)
			(layer "B.Fab")
		)
		(fp_line
			(start -0.12065 -0.3048)
			(end -0.67945 -0.3048)
			(stroke
				(width 0.1)
				(type default)
			)
			(layer "B.Fab")
		)
		(fp_line
			(start 0.12065 -0.305054)
			(end 0.12065 -0.2794)
			(stroke
				(width 0.1)
				(type default)
			)
			(layer "B.Fab")
		)
		(fp_line
			(start 0.67945 -0.305054)
			(end 0.12065 -0.305054)
			(stroke
				(width 0.1)
				(type default)
			)
			(layer "B.Fab")
		)
		(pad "1" smd circle
			(at 0.40005 0 90)
			(size 0 0)
			(layers "B.Cu" "B.Mask" "B.Paste")
			(net "HSC_VDD_R_1")
		)
		(pad "2" smd circle
			(at -0.40005 0 90)
			(size 0 0)
			(layers "B.Cu" "B.Mask" "B.Paste")
			(net "HSC_VDD")
		)
	)
	(footprint ""
		(layer "B.Cu")
		(at 290.948618 -149.992588 -90)
		(property "Reference" "R1821"
			(at 0 0 90)
			(layer "B.SilkS")
			(hide yes)
			(effects
				(font
					(size 1.27 1.27)
				)
				(justify mirror)
			)
		)
		(property "Value" ""
			(at 0 0 90)
			(layer "B.Fab")
			(effects
				(font
					(size 1.27 1.27)
				)
				(justify mirror)
			)
		)
		(duplicate_pad_numbers_are_jumpers no)
		(fp_line
			(start -0.7874 0.4064)
			(end 0.7874 0.4064)
			(stroke
				(width 0.1524)
				(type default)
			)
			(layer "B.SilkS")
		)
		(fp_line
			(start 0.7874 0.4064)
			(end 0.7874 -0.4064)
			(stroke
				(width 0.1524)
				(type default)
			)
			(layer "B.SilkS")
		)
		(fp_line
			(start -0.7874 -0.4064)
			(end -0.7874 0.4064)
			(stroke
				(width 0.1524)
				(type default)
			)
			(layer "B.SilkS")
		)
		(fp_line
			(start 0.7874 -0.4064)
			(end -0.7874 -0.4064)
			(stroke
				(width 0.1524)
				(type default)
			)
			(layer "B.SilkS")
		)
		(fp_line
			(start -0.67945 0.3048)
			(end -0.120396 0.3048)
			(stroke
				(width 0.1)
				(type default)
			)
			(layer "B.Fab")
		)
		(fp_line
			(start -0.120396 0.3048)
			(end -0.120396 0.2794)
			(stroke
				(width 0.1)
				(type default)
			)
			(layer "B.Fab")
		)
		(fp_line
			(start 0.12065 0.3048)
			(end 0.67945 0.3048)
			(stroke
				(width 0.1)
				(type default)
			)
			(layer "B.Fab")
		)
		(fp_line
			(start 0.67945 0.3048)
			(end 0.67945 -0.305054)
			(stroke
				(width 0.1)
				(type default)
			)
			(layer "B.Fab")
		)
		(fp_line
			(start -0.120396 0.2794)
			(end 0.12065 0.2794)
			(stroke
				(width 0.1)
				(type default)
			)
			(layer "B.Fab")
		)
		(fp_line
			(start 0.12065 0.2794)
			(end 0.12065 0.3048)
			(stroke
				(width 0.1)
				(type default)
			)
			(layer "B.Fab")
		)
		(fp_line
			(start -0.12065 -0.2794)
			(end -0.12065 -0.3048)
			(stroke
				(width 0.1)
				(type default)
			)
			(layer "B.Fab")
		)
		(fp_line
			(start 0.12065 -0.2794)
			(end -0.12065 -0.2794)
			(stroke
				(width 0.1)
				(type default)
			)
			(layer "B.Fab")
		)
		(fp_line
			(start -0.67945 -0.3048)
			(end -0.67945 0.3048)
			(stroke
				(width 0.1)
				(type default)
			)
			(layer "B.Fab")
		)
		(fp_line
			(start -0.12065 -0.3048)
			(end -0.67945 -0.3048)
			(stroke
				(width 0.1)
				(type default)
			)
			(layer "B.Fab")
		)
		(fp_line
			(start 0.12065 -0.305054)
			(end 0.12065 -0.2794)
			(stroke
				(width 0.1)
				(type default)
			)
			(layer "B.Fab")
		)
		(fp_line
			(start 0.67945 -0.305054)
			(end 0.12065 -0.305054)
			(stroke
				(width 0.1)
				(type default)
			)
			(layer "B.Fab")
		)
		(pad "1" smd circle
			(at 0.40005 0 90)
			(size 0 0)
			(layers "B.Cu" "B.Mask" "B.Paste")
			(net "FM_SPD_REMOTE_EN_R")
		)
		(pad "2" smd circle
			(at -0.40005 0 90)
			(size 0 0)
			(layers "B.Cu" "B.Mask" "B.Paste")
			(net "FM_SPD_REMOTE_EN")
		)
	)
	(footprint ""
		(layer "B.Cu")
		(at 308.902608 -250.785376 90)
		(property "Reference" "C520"
			(at 0 0 90)
			(layer "B.SilkS")
			(hide yes)
			(effects
				(font
					(size 1.27 1.27)
				)
				(justify mirror)
			)
		)
		(property "Value" ""
			(at 0 0 90)
			(layer "B.Fab")
			(effects
				(font
					(size 1.27 1.27)
				)
				(justify mirror)
			)
		)
		(duplicate_pad_numbers_are_jumpers no)
		(fp_line
			(start 1.524 -0.762)
			(end -1.524 -0.762)
			(stroke
				(width 0.1524)
				(type default)
			)
			(layer "B.SilkS")
		)
		(fp_line
			(start -1.524 -0.762)
			(end -1.524 0.762)
			(stroke
				(width 0.1524)
				(type default)
			)
			(layer "B.SilkS")
		)
		(fp_line
			(start 1.524 0.762)
			(end 1.524 -0.762)
			(stroke
				(width 0.1524)
				(type default)
			)
			(layer "B.SilkS")
		)
		(fp_line
			(start -1.524 0.762)
			(end 1.524 0.762)
			(stroke
				(width 0.1524)
				(type default)
			)
			(layer "B.SilkS")
		)
		(fp_line
			(start 1.1049 -0.724916)
			(end 1.1049 0.724916)
			(stroke
				(width 0.1)
				(type default)
			)
			(layer "B.Fab")
		)
		(fp_line
			(start -1.1049 -0.724916)
			(end 1.1049 -0.724916)
			(stroke
				(width 0.1)
				(type default)
			)
			(layer "B.Fab")
		)
		(fp_line
			(start 1.1049 0.724916)
			(end -1.1049 0.724916)
			(stroke
				(width 0.1)
				(type default)
			)
			(layer "B.Fab")
		)
		(fp_line
			(start -1.1049 0.724916)
			(end -1.1049 -0.724916)
			(stroke
				(width 0.1)
				(type default)
			)
			(layer "B.Fab")
		)
		(pad "1" smd rect
			(at 0.889 0 90)
			(size 1.016 1.27)
			(layers "B.Cu" "B.Mask" "B.Paste")
			(net "PVCCFA_EHV_FIVRA_CPU0")
		)
		(pad "2" smd rect
			(at -0.889 0 90)
			(size 1.016 1.27)
			(layers "B.Cu" "B.Mask" "B.Paste")
			(net "GND")
		)
	)
)
